(kicad_pcb
	(version 20260206)
	(generator "pcbnew")
	(generator_version "10.0")
	(general
		(thickness 1.6)
		(legacy_teardrops no)
	)
	(paper "A4")
	(title_block
		(title "12092022_DA0F0TMDCD0_F0T_Management_Board_D_brd_V3_OCP.brd")
		(comment 1 "Grand Teton / footprints 582-587 of 1440")
	)
	(layers
		(0 "F.Cu" signal "TOP")
		(4 "In1.Cu" signal "GND")
		(6 "In2.Cu" signal "IN1")
		(8 "In3.Cu" signal "GND1")
		(10 "In4.Cu" signal "IN2")
		(12 "In5.Cu" signal "VCC")
		(14 "In6.Cu" signal "VCC1")
		(16 "In7.Cu" signal "IN3")
		(18 "In8.Cu" signal "GND2")
		(20 "In9.Cu" signal "IN4")
		(22 "In10.Cu" signal "GND3")
		(2 "B.Cu" signal "BOTTOM")
		(9 "F.Adhes" user "F.Adhesive")
		(11 "B.Adhes" user "B.Adhesive")
		(13 "F.Paste" user "Package Geometry/Pastemask Top")
		(15 "B.Paste" user "Package Geometry/Pastemask Bottom")
		(5 "F.SilkS" user "Ref Des/Silkscreen Top")
		(7 "B.SilkS" user "Ref Des/Silkscreen Bottom")
		(1 "F.Mask" user "Board Geometry/Soldermask Top")
		(3 "B.Mask" user "Board Geometry/Soldermask Bottom")
		(17 "Dwgs.User" user "User.Drawings")
		(19 "Cmts.User" user "User.Comments")
		(21 "Eco1.User" user "User.Eco1")
		(23 "Eco2.User" user "User.Eco2")
		(25 "Edge.Cuts" user "Board Geometry/Outline")
		(27 "Margin" user)
		(31 "F.CrtYd" user "Package Geometry/Place Bound Top")
		(29 "B.CrtYd" user "Package Geometry/Place Bound Bottom")
		(35 "F.Fab" user "Ref Des/Assembly Top")
		(33 "B.Fab" user "Ref Des/Assembly Bottom")
	)
	(footprint ""
		(layer "F.Cu")
		(at 37.68598 -44.1325 -90)
		(property "Reference" "R269"
			(at 0 0 270)
			(layer "F.SilkS")
			(hide yes)
			(effects
				(font
					(size 1.27 1.27)
				)
			)
		)
		(property "Value" ""
			(at 0 0 270)
			(layer "F.Fab")
			(effects
				(font
					(size 1.27 1.27)
				)
			)
		)
		(duplicate_pad_numbers_are_jumpers no)
		(fp_line
			(start -0.7874 0.4064)
			(end -0.7874 -0.4064)
			(stroke
				(width 0.1524)
				(type default)
			)
			(layer "F.SilkS")
		)
		(fp_line
			(start 0.7874 0.4064)
			(end -0.7874 0.4064)
			(stroke
				(width 0.1524)
				(type default)
			)
			(layer "F.SilkS")
		)
		(fp_line
			(start -0.7874 -0.4064)
			(end 0.7874 -0.4064)
			(stroke
				(width 0.1524)
				(type default)
			)
			(layer "F.SilkS")
		)
		(fp_line
			(start 0.7874 -0.4064)
			(end 0.7874 0.4064)
			(stroke
				(width 0.1524)
				(type default)
			)
			(layer "F.SilkS")
		)
		(fp_line
			(start -0.67945 0.3048)
			(end -0.67945 -0.305054)
			(stroke
				(width 0.1)
				(type default)
			)
			(layer "F.Fab")
		)
		(fp_line
			(start -0.12065 0.3048)
			(end -0.67945 0.3048)
			(stroke
				(width 0.1)
				(type default)
			)
			(layer "F.Fab")
		)
		(fp_line
			(start 0.120396 0.3048)
			(end 0.120396 0.2794)
			(stroke
				(width 0.1)
				(type default)
			)
			(layer "F.Fab")
		)
		(fp_line
			(start 0.67945 0.3048)
			(end 0.120396 0.3048)
			(stroke
				(width 0.1)
				(type default)
			)
			(layer "F.Fab")
		)
		(fp_line
			(start -0.12065 0.2794)
			(end -0.12065 0.3048)
			(stroke
				(width 0.1)
				(type default)
			)
			(layer "F.Fab")
		)
		(fp_line
			(start 0.120396 0.2794)
			(end -0.12065 0.2794)
			(stroke
				(width 0.1)
				(type default)
			)
			(layer "F.Fab")
		)
		(fp_line
			(start -0.12065 -0.2794)
			(end 0.12065 -0.2794)
			(stroke
				(width 0.1)
				(type default)
			)
			(layer "F.Fab")
		)
		(fp_line
			(start 0.12065 -0.2794)
			(end 0.12065 -0.3048)
			(stroke
				(width 0.1)
				(type default)
			)
			(layer "F.Fab")
		)
		(fp_line
			(start 0.12065 -0.3048)
			(end 0.67945 -0.3048)
			(stroke
				(width 0.1)
				(type default)
			)
			(layer "F.Fab")
		)
		(fp_line
			(start 0.67945 -0.3048)
			(end 0.67945 0.3048)
			(stroke
				(width 0.1)
				(type default)
			)
			(layer "F.Fab")
		)
		(fp_line
			(start -0.67945 -0.305054)
			(end -0.12065 -0.305054)
			(stroke
				(width 0.1)
				(type default)
			)
			(layer "F.Fab")
		)
		(fp_line
			(start -0.12065 -0.305054)
			(end -0.12065 -0.2794)
			(stroke
				(width 0.1)
				(type default)
			)
			(layer "F.Fab")
		)
		(pad "1" smd circle
			(at -0.40005 0 270)
			(size 0 0)
			(layers "F.Cu" "F.Mask" "F.Paste")
			(net "P3V3_AUX")
		)
		(pad "2" smd circle
			(at 0.40005 0 270)
			(size 0 0)
			(layers "F.Cu" "F.Mask" "F.Paste")
			(net "SMB_BMC_ALERT4_N")
		)
	)
	(footprint ""
		(layer "F.Cu")
		(at 70.358 -11.684 -90)
		(property "Reference" "C336"
			(at 0 0 270)
			(layer "F.SilkS")
			(hide yes)
			(effects
				(font
					(size 1.27 1.27)
				)
			)
		)
		(property "Value" ""
			(at 0 0 270)
			(layer "F.Fab")
			(effects
				(font
					(size 1.27 1.27)
				)
			)
		)
		(duplicate_pad_numbers_are_jumpers no)
		(fp_line
			(start -0.7874 0.4064)
			(end -0.7874 -0.4064)
			(stroke
				(width 0.1524)
				(type default)
			)
			(layer "F.SilkS")
		)
		(fp_line
			(start 0.7874 0.4064)
			(end -0.7874 0.4064)
			(stroke
				(width 0.1524)
				(type default)
			)
			(layer "F.SilkS")
		)
		(fp_line
			(start -0.7874 -0.4064)
			(end 0.7874 -0.4064)
			(stroke
				(width 0.1524)
				(type default)
			)
			(layer "F.SilkS")
		)
		(fp_line
			(start 0.7874 -0.4064)
			(end 0.7874 0.4064)
			(stroke
				(width 0.1524)
				(type default)
			)
			(layer "F.SilkS")
		)
		(fp_line
			(start -0.67945 0.3048)
			(end -0.67945 -0.305054)
			(stroke
				(width 0.1)
				(type default)
			)
			(layer "F.Fab")
		)
		(fp_line
			(start -0.12065 0.3048)
			(end -0.67945 0.3048)
			(stroke
				(width 0.1)
				(type default)
			)
			(layer "F.Fab")
		)
		(fp_line
			(start 0.120396 0.3048)
			(end 0.120396 0.2794)
			(stroke
				(width 0.1)
				(type default)
			)
			(layer "F.Fab")
		)
		(fp_line
			(start 0.67945 0.3048)
			(end 0.120396 0.3048)
			(stroke
				(width 0.1)
				(type default)
			)
			(layer "F.Fab")
		)
		(fp_line
			(start -0.12065 0.2794)
			(end -0.12065 0.3048)
			(stroke
				(width 0.1)
				(type default)
			)
			(layer "F.Fab")
		)
		(fp_line
			(start 0.120396 0.2794)
			(end -0.12065 0.2794)
			(stroke
				(width 0.1)
				(type default)
			)
			(layer "F.Fab")
		)
		(fp_line
			(start -0.12065 -0.2794)
			(end 0.12065 -0.2794)
			(stroke
				(width 0.1)
				(type default)
			)
			(layer "F.Fab")
		)
		(fp_line
			(start 0.12065 -0.2794)
			(end 0.12065 -0.3048)
			(stroke
				(width 0.1)
				(type default)
			)
			(layer "F.Fab")
		)
		(fp_line
			(start 0.12065 -0.3048)
			(end 0.67945 -0.3048)
			(stroke
				(width 0.1)
				(type default)
			)
			(layer "F.Fab")
		)
		(fp_line
			(start 0.67945 -0.3048)
			(end 0.67945 0.3048)
			(stroke
				(width 0.1)
				(type default)
			)
			(layer "F.Fab")
		)
		(fp_line
			(start -0.67945 -0.305054)
			(end -0.12065 -0.305054)
			(stroke
				(width 0.1)
				(type default)
			)
			(layer "F.Fab")
		)
		(fp_line
			(start -0.12065 -0.305054)
			(end -0.12065 -0.2794)
			(stroke
				(width 0.1)
				(type default)
			)
			(layer "F.Fab")
		)
		(pad "1" smd circle
			(at -0.40005 0 270)
			(size 0 0)
			(layers "F.Cu" "F.Mask" "F.Paste")
			(net "P3V3_AUX")
		)
		(pad "2" smd circle
			(at 0.40005 0 270)
			(size 0 0)
			(layers "F.Cu" "F.Mask" "F.Paste")
			(net "GND")
		)
	)
	(footprint ""
		(layer "F.Cu")
		(at 77.281786 -31.307786 90)
		(property "Reference" "D5"
			(at -3.621786 7.580884 90)
			(unlocked yes)
			(layer "F.SilkS")
			(effects
				(font
					(size 0.7874 0.5842)
					(thickness 0.1524)
				)
				(justify left)
			)
		)
		(property "Value" ""
			(at 0 0 90)
			(layer "F.Fab")
			(effects
				(font
					(size 1.27 1.27)
				)
			)
		)
		(duplicate_pad_numbers_are_jumpers no)
		(fp_line
			(start 1.778 -0.5588)
			(end 1.3208 -0.5588)
			(stroke
				(width 0.1524)
				(type default)
			)
			(layer "F.SilkS")
		)
		(fp_line
			(start 1.778 -0.5588)
			(end 1.778 0.5588)
			(stroke
				(width 0.1524)
				(type default)
			)
			(layer "F.SilkS")
		)
		(fp_line
			(start 1.4732 -0.5588)
			(end 1.4732 0.5588)
			(stroke
				(width 0.1524)
				(type default)
			)
			(layer "F.SilkS")
		)
		(fp_line
			(start 1.3208 -0.5588)
			(end 1.3208 0.5588)
			(stroke
				(width 0.1524)
				(type default)
			)
			(layer "F.SilkS")
		)
		(fp_line
			(start -1.3208 -0.5588)
			(end 1.3208 -0.5588)
			(stroke
				(width 0.1524)
				(type default)
			)
			(layer "F.SilkS")
		)
		(fp_line
			(start 1.778 0.5588)
			(end 1.3208 0.5588)
			(stroke
				(width 0.1524)
				(type default)
			)
			(layer "F.SilkS")
		)
		(fp_line
			(start 1.6256 0.5588)
			(end 1.6256 -0.5588)
			(stroke
				(width 0.1524)
				(type default)
			)
			(layer "F.SilkS")
		)
		(fp_line
			(start 1.3208 0.5588)
			(end -1.3208 0.5588)
			(stroke
				(width 0.1524)
				(type default)
			)
			(layer "F.SilkS")
		)
		(fp_line
			(start -1.3208 0.5588)
			(end -1.3208 -0.5588)
			(stroke
				(width 0.1524)
				(type default)
			)
			(layer "F.SilkS")
		)
		(fp_line
			(start 0.8001 -0.40005)
			(end 0.8001 0.40005)
			(stroke
				(width 0.1)
				(type default)
			)
			(layer "F.Fab")
		)
		(fp_line
			(start -0.8001 -0.40005)
			(end 0.8001 -0.40005)
			(stroke
				(width 0.1)
				(type default)
			)
			(layer "F.Fab")
		)
		(fp_line
			(start 0.8001 0.40005)
			(end -0.8001 0.40005)
			(stroke
				(width 0.1)
				(type default)
			)
			(layer "F.Fab")
		)
		(fp_line
			(start -0.8001 0.40005)
			(end -0.8001 -0.40005)
			(stroke
				(width 0.1)
				(type default)
			)
			(layer "F.Fab")
		)
		(fp_text user "-"
			(at 1.661414 -1.024636 90)
			(unlocked yes)
			(layer "F.SilkS")
			(effects
				(font
					(size 1.905 1.4224)
					(thickness 0.1524)
				)
				(justify left)
			)
		)
		(fp_text user "+"
			(at -0.853186 -0.605536 270)
			(unlocked yes)
			(layer "F.SilkS")
			(effects
				(font
					(size 1.905 1.4224)
					(thickness 0.1524)
				)
				(justify left)
			)
		)
		(fp_text user "-"
			(at 1.6256 -0.22225 90)
			(unlocked yes)
			(layer "F.Fab")
			(effects
				(font
					(size 1.905 1.4224)
					(thickness 0.1524)
				)
				(justify left)
			)
		)
		(fp_text user "+"
			(at -2.5654 -0.22225 90)
			(unlocked yes)
			(layer "F.Fab")
			(effects
				(font
					(size 1.905 1.4224)
					(thickness 0.1524)
				)
				(justify left)
			)
		)
		(pad "A" smd rect
			(at -0.750062 0 90)
			(size 0.8128 0.8128)
			(layers "F.Cu" "F.Mask" "F.Paste")
			(net "LED_POSTCODE_5_R")
		)
		(pad "C" smd rect
			(at 0.750062 0 90)
			(size 0.8128 0.8128)
			(layers "F.Cu" "F.Mask" "F.Paste")
			(net "GND")
		)
	)
	(footprint ""
		(layer "F.Cu")
		(at 10.922 -105.5878)
		(property "Reference" "R315"
			(at 0 0 0)
			(layer "F.SilkS")
			(hide yes)
			(effects
				(font
					(size 1.27 1.27)
				)
			)
		)
		(property "Value" ""
			(at 0 0 0)
			(layer "F.Fab")
			(effects
				(font
					(size 1.27 1.27)
				)
			)
		)
		(duplicate_pad_numbers_are_jumpers no)
		(fp_line
			(start -0.7874 -0.4064)
			(end 0.7874 -0.4064)
			(stroke
				(width 0.1524)
				(type default)
			)
			(layer "F.SilkS")
		)
		(fp_line
			(start -0.7874 0.4064)
			(end -0.7874 -0.4064)
			(stroke
				(width 0.1524)
				(type default)
			)
			(layer "F.SilkS")
		)
		(fp_line
			(start 0.7874 -0.4064)
			(end 0.7874 0.4064)
			(stroke
				(width 0.1524)
				(type default)
			)
			(layer "F.SilkS")
		)
		(fp_line
			(start 0.7874 0.4064)
			(end -0.7874 0.4064)
			(stroke
				(width 0.1524)
				(type default)
			)
			(layer "F.SilkS")
		)
		(fp_line
			(start -0.67945 -0.305054)
			(end -0.12065 -0.305054)
			(stroke
				(width 0.1)
				(type default)
			)
			(layer "F.Fab")
		)
		(fp_line
			(start -0.67945 0.3048)
			(end -0.67945 -0.305054)
			(stroke
				(width 0.1)
				(type default)
			)
			(layer "F.Fab")
		)
		(fp_line
			(start -0.12065 -0.305054)
			(end -0.12065 -0.2794)
			(stroke
				(width 0.1)
				(type default)
			)
			(layer "F.Fab")
		)
		(fp_line
			(start -0.12065 -0.2794)
			(end 0.12065 -0.2794)
			(stroke
				(width 0.1)
				(type default)
			)
			(layer "F.Fab")
		)
		(fp_line
			(start -0.12065 0.2794)
			(end -0.12065 0.3048)
			(stroke
				(width 0.1)
				(type default)
			)
			(layer "F.Fab")
		)
		(fp_line
			(start -0.12065 0.3048)
			(end -0.67945 0.3048)
			(stroke
				(width 0.1)
				(type default)
			)
			(layer "F.Fab")
		)
		(fp_line
			(start 0.120396 0.2794)
			(end -0.12065 0.2794)
			(stroke
				(width 0.1)
				(type default)
			)
			(layer "F.Fab")
		)
		(fp_line
			(start 0.120396 0.3048)
			(end 0.120396 0.2794)
			(stroke
				(width 0.1)
				(type default)
			)
			(layer "F.Fab")
		)
		(fp_line
			(start 0.12065 -0.3048)
			(end 0.67945 -0.3048)
			(stroke
				(width 0.1)
				(type default)
			)
			(layer "F.Fab")
		)
		(fp_line
			(start 0.12065 -0.2794)
			(end 0.12065 -0.3048)
			(stroke
				(width 0.1)
				(type default)
			)
			(layer "F.Fab")
		)
		(fp_line
			(start 0.67945 -0.3048)
			(end 0.67945 0.3048)
			(stroke
				(width 0.1)
				(type default)
			)
			(layer "F.Fab")
		)
		(fp_line
			(start 0.67945 0.3048)
			(end 0.120396 0.3048)
			(stroke
				(width 0.1)
				(type default)
			)
			(layer "F.Fab")
		)
		(pad "1" smd circle
			(at -0.40005 0)
			(size 0 0)
			(layers "F.Cu" "F.Mask" "F.Paste")
			(net "RST_BMC_SRST_BUF_R_N")
		)
		(pad "2" smd circle
			(at 0.40005 0)
			(size 0 0)
			(layers "F.Cu" "F.Mask" "F.Paste")
			(net "RST_BMC_SRST_BUF_R1_N")
		)
	)
	(footprint ""
		(layer "F.Cu")
		(at 30.5562 -88.9762)
		(property "Reference" "R809"
			(at 0 0 0)
			(layer "F.SilkS")
			(hide yes)
			(effects
				(font
					(size 1.27 1.27)
				)
			)
		)
		(property "Value" ""
			(at 0 0 0)
			(layer "F.Fab")
			(effects
				(font
					(size 1.27 1.27)
				)
			)
		)
		(duplicate_pad_numbers_are_jumpers no)
		(fp_line
			(start -0.7874 -0.4064)
			(end 0.7874 -0.4064)
			(stroke
				(width 0.1524)
				(type default)
			)
			(layer "F.SilkS")
		)
		(fp_line
			(start -0.7874 0.4064)
			(end -0.7874 -0.4064)
			(stroke
				(width 0.1524)
				(type default)
			)
			(layer "F.SilkS")
		)
		(fp_line
			(start 0.7874 -0.4064)
			(end 0.7874 0.4064)
			(stroke
				(width 0.1524)
				(type default)
			)
			(layer "F.SilkS")
		)
		(fp_line
			(start 0.7874 0.4064)
			(end -0.7874 0.4064)
			(stroke
				(width 0.1524)
				(type default)
			)
			(layer "F.SilkS")
		)
		(fp_line
			(start -0.67945 -0.305054)
			(end -0.12065 -0.305054)
			(stroke
				(width 0.1)
				(type default)
			)
			(layer "F.Fab")
		)
		(fp_line
			(start -0.67945 0.3048)
			(end -0.67945 -0.305054)
			(stroke
				(width 0.1)
				(type default)
			)
			(layer "F.Fab")
		)
		(fp_line
			(start -0.12065 -0.305054)
			(end -0.12065 -0.2794)
			(stroke
				(width 0.1)
				(type default)
			)
			(layer "F.Fab")
		)
		(fp_line
			(start -0.12065 -0.2794)
			(end 0.12065 -0.2794)
			(stroke
				(width 0.1)
				(type default)
			)
			(layer "F.Fab")
		)
		(fp_line
			(start -0.12065 0.2794)
			(end -0.12065 0.3048)
			(stroke
				(width 0.1)
				(type default)
			)
			(layer "F.Fab")
		)
		(fp_line
			(start -0.12065 0.3048)
			(end -0.67945 0.3048)
			(stroke
				(width 0.1)
				(type default)
			)
			(layer "F.Fab")
		)
		(fp_line
			(start 0.120396 0.2794)
			(end -0.12065 0.2794)
			(stroke
				(width 0.1)
				(type default)
			)
			(layer "F.Fab")
		)
		(fp_line
			(start 0.120396 0.3048)
			(end 0.120396 0.2794)
			(stroke
				(width 0.1)
				(type default)
			)
			(layer "F.Fab")
		)
		(fp_line
			(start 0.12065 -0.3048)
			(end 0.67945 -0.3048)
			(stroke
				(width 0.1)
				(type default)
			)
			(layer "F.Fab")
		)
		(fp_line
			(start 0.12065 -0.2794)
			(end 0.12065 -0.3048)
			(stroke
				(width 0.1)
				(type default)
			)
			(layer "F.Fab")
		)
		(fp_line
			(start 0.67945 -0.3048)
			(end 0.67945 0.3048)
			(stroke
				(width 0.1)
				(type default)
			)
			(layer "F.Fab")
		)
		(fp_line
			(start 0.67945 0.3048)
			(end 0.120396 0.3048)
			(stroke
				(width 0.1)
				(type default)
			)
			(layer "F.Fab")
		)
		(pad "1" smd circle
			(at -0.40005 0)
			(size 0 0)
			(layers "F.Cu" "F.Mask" "F.Paste")
			(net "PU_FPGA_NCONFIG")
		)
		(pad "2" smd circle
			(at 0.40005 0)
			(size 0 0)
			(layers "F.Cu" "F.Mask" "F.Paste")
			(net "PVCCIO_AUX_PLD")
		)
	)
	(footprint ""
		(layer "F.Cu")
		(at 42.950638 -22.15642 -90)
		(property "Reference" "R675"
			(at 0 0 270)
			(layer "F.SilkS")
			(hide yes)
			(effects
				(font
					(size 1.27 1.27)
				)
			)
		)
		(property "Value" ""
			(at 0 0 270)
			(layer "F.Fab")
			(effects
				(font
					(size 1.27 1.27)
				)
			)
		)
		(duplicate_pad_numbers_are_jumpers no)
		(fp_line
			(start 0.7874 0.4064)
			(end -0.7874 0.4064)
			(stroke
				(width 0.1524)
				(type default)
			)
			(layer "F.SilkS")
		)
		(fp_line
			(start -0.7874 -0.4064)
			(end 0.7874 -0.4064)
			(stroke
				(width 0.1524)
				(type default)
			)
			(layer "F.SilkS")
		)
		(fp_line
			(start -0.67945 0.3048)
			(end -0.67945 -0.305054)
			(stroke
				(width 0.1)
				(type default)
			)
			(layer "F.Fab")
		)
		(fp_line
			(start -0.12065 0.3048)
			(end -0.67945 0.3048)
			(stroke
				(width 0.1)
				(type default)
			)
			(layer "F.Fab")
		)
		(fp_line
			(start 0.120396 0.3048)
			(end 0.120396 0.2794)
			(stroke
				(width 0.1)
				(type default)
			)
			(layer "F.Fab")
		)
		(fp_line
			(start 0.67945 0.3048)
			(end 0.120396 0.3048)
			(stroke
				(width 0.1)
				(type default)
			)
			(layer "F.Fab")
		)
		(fp_line
			(start -0.12065 0.2794)
			(end -0.12065 0.3048)
			(stroke
				(width 0.1)
				(type default)
			)
			(layer "F.Fab")
		)
		(fp_line
			(start 0.120396 0.2794)
			(end -0.12065 0.2794)
			(stroke
				(width 0.1)
				(type default)
			)
			(layer "F.Fab")
		)
		(fp_line
			(start -0.12065 -0.2794)
			(end 0.12065 -0.2794)
			(stroke
				(width 0.1)
				(type default)
			)
			(layer "F.Fab")
		)
		(fp_line
			(start 0.12065 -0.2794)
			(end 0.12065 -0.3048)
			(stroke
				(width 0.1)
				(type default)
			)
			(layer "F.Fab")
		)
		(fp_line
			(start 0.12065 -0.3048)
			(end 0.67945 -0.3048)
			(stroke
				(width 0.1)
				(type default)
			)
			(layer "F.Fab")
		)
		(fp_line
			(start 0.67945 -0.3048)
			(end 0.67945 0.3048)
			(stroke
				(width 0.1)
				(type default)
			)
			(layer "F.Fab")
		)
		(fp_line
			(start -0.67945 -0.305054)
			(end -0.12065 -0.305054)
			(stroke
				(width 0.1)
				(type default)
			)
			(layer "F.Fab")
		)
		(fp_line
			(start -0.12065 -0.305054)
			(end -0.12065 -0.2794)
			(stroke
				(width 0.1)
				(type default)
			)
			(layer "F.Fab")
		)
		(pad "1" smd circle
			(at -0.40005 0 270)
			(size 0 0)
			(layers "F.Cu" "F.Mask" "F.Paste")
			(net "USB3_01_MUX_FB_RXP")
		)
		(pad "2" smd circle
			(at 0.40005 0 270)
			(size 0 0)
			(layers "F.Cu" "F.Mask" "F.Paste")
			(net "USB3_01_FB_RXP")
		)
	)
)
